# T6G (Grand Teton) — schematic netlist excerpt (pin names and nets, part order shuffled) for the footprints in the layout excerpt that follows; sources: Cadence DE-HDL packaged netlist, KiCad conversion of 04192023_DAF0TMB3IC0_F0TG_MB_C_brd_V02_OCP.brd

R1289  Q_RES  100K 1% CHIP  pkg 0402LF  page 132 : A = FB_BMC_ISOLATE ; B = GND
C5018  Q_CAP  1000PF 50V 5% X7R  pkg 0402  page 193 : A = GND ; B = PWRGD_PVDDCR_SOC_P0

(kicad_pcb
	(version 20260206)
	(generator "pcbnew")
	(generator_version "10.0")
	(general
		(thickness 1.6)
		(legacy_teardrops no)
	)
	(paper "A4")
	(title_block
		(title "04192023_DAF0TMB3IC0_F0TG_MB_C_brd_V02_OCP.brd")
		(comment 1 "Grand Teton / footprints 676-677 of 8354")
	)
	(layers
		(0 "F.Cu" signal "TOP")
		(4 "In1.Cu" signal "GND")
		(6 "In2.Cu" signal "IN1")
		(8 "In3.Cu" signal "GND1")
		(10 "In4.Cu" signal "IN2")
		(12 "In5.Cu" signal "GND2")
		(14 "In6.Cu" signal "IN3")
		(16 "In7.Cu" signal "GND3")
		(18 "In8.Cu" signal "VCC")
		(20 "In9.Cu" signal "VCC1")
		(22 "In10.Cu" signal "GND4")
		(24 "In11.Cu" signal "IN4")
		(26 "In12.Cu" signal "GND5")
		(28 "In13.Cu" signal "IN5")
		(30 "In14.Cu" signal "GND6")
		(32 "In15.Cu" signal "IN6")
		(34 "In16.Cu" signal "GND7")
		(2 "B.Cu" signal "BOTTOM")
		(9 "F.Adhes" user "F.Adhesive")
		(11 "B.Adhes" user "B.Adhesive")
		(13 "F.Paste" user "Package Geometry/Pastemask Top")
		(15 "B.Paste" user "Package Geometry/Pastemask Bottom")
		(5 "F.SilkS" user "Ref Des/Silkscreen Top")
		(7 "B.SilkS" user "Ref Des/Silkscreen Bottom")
		(1 "F.Mask" user "Board Geometry/Soldermask Top")
		(3 "B.Mask" user "Board Geometry/Soldermask Bottom")
		(17 "Dwgs.User" user "User.Drawings")
		(19 "Cmts.User" user "User.Comments")
		(21 "Eco1.User" user "User.Eco1")
		(23 "Eco2.User" user "User.Eco2")
		(25 "Edge.Cuts" user "Board Geometry/Outline")
		(27 "Margin" user)
		(31 "F.CrtYd" user "Package Geometry/Place Bound Top")
		(29 "B.CrtYd" user "Package Geometry/Place Bound Bottom")
		(35 "F.Fab" user "Ref Des/Assembly Top")
		(33 "B.Fab" user "Ref Des/Assembly Bottom")
	)
	(footprint ""
		(layer "F.Cu")
		(at 463.462624 -98.564954 180)
		(property "Reference" "R1289"
			(at 0 0 180)
			(layer "F.SilkS")
			(hide yes)
			(effects
				(font
					(size 1.27 1.27)
				)
			)
		)
		(property "Value" ""
			(at 0 0 180)
			(layer "F.Fab")
			(effects
				(font
					(size 1.27 1.27)
				)
			)
		)
		(duplicate_pad_numbers_are_jumpers no)
		(fp_line
			(start 0.7874 0.4064)
			(end -0.7874 0.4064)
			(stroke
				(width 0.1524)
				(type default)
			)
			(layer "F.SilkS")
		)
		(fp_line
			(start 0.7874 -0.4064)
			(end 0.7874 0.4064)
			(stroke
				(width 0.1524)
				(type default)
			)
			(layer "F.SilkS")
		)
		(fp_line
			(start -0.7874 0.4064)
			(end -0.7874 -0.4064)
			(stroke
				(width 0.1524)
				(type default)
			)
			(layer "F.SilkS")
		)
		(fp_line
			(start -0.7874 -0.4064)
			(end 0.7874 -0.4064)
			(stroke
				(width 0.1524)
				(type default)
			)
			(layer "F.SilkS")
		)
		(fp_line
			(start 0.67945 0.3048)
			(end 0.120396 0.3048)
			(stroke
				(width 0.1)
				(type default)
			)
			(layer "F.Fab")
		)
		(fp_line
			(start 0.67945 -0.3048)
			(end 0.67945 0.3048)
			(stroke
				(width 0.1)
				(type default)
			)
			(layer "F.Fab")
		)
		(fp_line
			(start 0.12065 -0.2794)
			(end 0.12065 -0.3048)
			(stroke
				(width 0.1)
				(type default)
			)
			(layer "F.Fab")
		)
		(fp_line
			(start 0.12065 -0.3048)
			(end 0.67945 -0.3048)
			(stroke
				(width 0.1)
				(type default)
			)
			(layer "F.Fab")
		)
		(fp_line
			(start 0.120396 0.3048)
			(end 0.120396 0.2794)
			(stroke
				(width 0.1)
				(type default)
			)
			(layer "F.Fab")
		)
		(fp_line
			(start 0.120396 0.2794)
			(end -0.12065 0.2794)
			(stroke
				(width 0.1)
				(type default)
			)
			(layer "F.Fab")
		)
		(fp_line
			(start -0.12065 0.3048)
			(end -0.67945 0.3048)
			(stroke
				(width 0.1)
				(type default)
			)
			(layer "F.Fab")
		)
		(fp_line
			(start -0.12065 0.2794)
			(end -0.12065 0.3048)
			(stroke
				(width 0.1)
				(type default)
			)
			(layer "F.Fab")
		)
		(fp_line
			(start -0.12065 -0.2794)
			(end 0.12065 -0.2794)
			(stroke
				(width 0.1)
				(type default)
			)
			(layer "F.Fab")
		)
		(fp_line
			(start -0.12065 -0.305054)
			(end -0.12065 -0.2794)
			(stroke
				(width 0.1)
				(type default)
			)
			(layer "F.Fab")
		)
		(fp_line
			(start -0.67945 0.3048)
			(end -0.67945 -0.305054)
			(stroke
				(width 0.1)
				(type default)
			)
			(layer "F.Fab")
		)
		(fp_line
			(start -0.67945 -0.305054)
			(end -0.12065 -0.305054)
			(stroke
				(width 0.1)
				(type default)
			)
			(layer "F.Fab")
		)
		(pad "1" smd circle
			(at -0.40005 0 180)
			(size 0 0)
			(layers "F.Cu" "F.Mask" "F.Paste")
			(net "FB_BMC_ISOLATE")
		)
		(pad "2" smd circle
			(at 0.40005 0 180)
			(size 0 0)
			(layers "F.Cu" "F.Mask" "F.Paste")
			(net "GND")
		)
	)
	(footprint ""
		(layer "F.Cu")
		(at 370.905278 -143.504158)
		(property "Reference" "C5018"
			(at 0 0 0)
			(layer "F.SilkS")
			(hide yes)
			(effects
				(font
					(size 1.27 1.27)
				)
			)
		)
		(property "Value" ""
			(at 0 0 0)
			(layer "F.Fab")
			(effects
				(font
					(size 1.27 1.27)
				)
			)
		)
		(duplicate_pad_numbers_are_jumpers no)
		(fp_line
			(start -0.7874 -0.4064)
			(end 0.7874 -0.4064)
			(stroke
				(width 0.1524)
				(type default)
			)
			(layer "F.SilkS")
		)
		(fp_line
			(start -0.7874 0.4064)
			(end -0.7874 -0.4064)
			(stroke
				(width 0.1524)
				(type default)
			)
			(layer "F.SilkS")
		)
		(fp_line
			(start 0.7874 -0.4064)
			(end 0.7874 0.4064)
			(stroke
				(width 0.1524)
				(type default)
			)
			(layer "F.SilkS")
		)
		(fp_line
			(start 0.7874 0.4064)
			(end -0.7874 0.4064)
			(stroke
				(width 0.1524)
				(type default)
			)
			(layer "F.SilkS")
		)
		(fp_line
			(start -0.67945 -0.305054)
			(end -0.12065 -0.305054)
			(stroke
				(width 0.1)
				(type default)
			)
			(layer "F.Fab")
		)
		(fp_line
			(start -0.67945 0.3048)
			(end -0.67945 -0.305054)
			(stroke
				(width 0.1)
				(type default)
			)
			(layer "F.Fab")
		)
		(fp_line
			(start -0.12065 -0.305054)
			(end -0.12065 -0.2794)
			(stroke
				(width 0.1)
				(type default)
			)
			(layer "F.Fab")
		)
		(fp_line
			(start -0.12065 -0.2794)
			(end 0.12065 -0.2794)
			(stroke
				(width 0.1)
				(type default)
			)
			(layer "F.Fab")
		)
		(fp_line
			(start -0.12065 0.2794)
			(end -0.12065 0.3048)
			(stroke
				(width 0.1)
				(type default)
			)
			(layer "F.Fab")
		)
		(fp_line
			(start -0.12065 0.3048)
			(end -0.67945 0.3048)
			(stroke
				(width 0.1)
				(type default)
			)
			(layer "F.Fab")
		)
		(fp_line
			(start 0.120396 0.2794)
			(end -0.12065 0.2794)
			(stroke
				(width 0.1)
				(type default)
			)
			(layer "F.Fab")
		)
		(fp_line
			(start 0.120396 0.3048)
			(end 0.120396 0.2794)
			(stroke
				(width 0.1)
				(type default)
			)
			(layer "F.Fab")
		)
		(fp_line
			(start 0.12065 -0.3048)
			(end 0.67945 -0.3048)
			(stroke
				(width 0.1)
				(type default)
			)
			(layer "F.Fab")
		)
		(fp_line
			(start 0.12065 -0.2794)
			(end 0.12065 -0.3048)
			(stroke
				(width 0.1)
				(type default)
			)
			(layer "F.Fab")
		)
		(fp_line
			(start 0.67945 -0.3048)
			(end 0.67945 0.3048)
			(stroke
				(width 0.1)
				(type default)
			)
			(layer "F.Fab")
		)
		(fp_line
			(start 0.67945 0.3048)
			(end 0.120396 0.3048)
			(stroke
				(width 0.1)
				(type default)
			)
			(layer "F.Fab")
		)
		(pad "1" smd circle
			(at -0.40005 0)
			(size 0 0)
			(layers "F.Cu" "F.Mask" "F.Paste")
			(net "GND")
		)
		(pad "2" smd circle
			(at 0.40005 0)
			(size 0 0)
			(layers "F.Cu" "F.Mask" "F.Paste")
			(net "PWRGD_PVDDCR_SOC_P0")
		)
	)
)
